(kicad_pcb
	(version 20260206)
	(generator "pcbnew")
	(generator_version "10.0")
	(general
		(thickness 1.6)
		(legacy_teardrops no)
	)
	(paper "A4")
	(title_block
		(title "baseboard — 13948-1b.1110WZS1818.brd")
		(comment 1 "Honey Badger (Wiwynn) / footprints 944-947 of 2523")
	)
	(layers
		(0 "F.Cu" signal "TOP")
		(4 "In1.Cu" signal "L2GND")
		(6 "In2.Cu" signal "L3")
		(8 "In3.Cu" signal "L4VCC")
		(10 "In4.Cu" signal "L5VCC")
		(12 "In5.Cu" signal "L6")
		(14 "In6.Cu" signal "L7GND")
		(2 "B.Cu" signal "BOTTOM")
		(9 "F.Adhes" user "F.Adhesive")
		(11 "B.Adhes" user "B.Adhesive")
		(13 "F.Paste" user "Package Geometry/Pastemask Top")
		(15 "B.Paste" user "Package Geometry/Pastemask Bottom")
		(5 "F.SilkS" user "Ref Des/Silkscreen Top")
		(7 "B.SilkS" user "Ref Des/Silkscreen Bottom")
		(1 "F.Mask" user "Board Geometry/Soldermask Top")
		(3 "B.Mask" user "Board Geometry/Soldermask Bottom")
		(17 "Dwgs.User" user "User.Drawings")
		(19 "Cmts.User" user "User.Comments")
		(21 "Eco1.User" user "User.Eco1")
		(23 "Eco2.User" user "User.Eco2")
		(25 "Edge.Cuts" user "Board Geometry/Outline")
		(27 "Margin" user)
		(31 "F.CrtYd" user "Package Geometry/Place Bound Top")
		(29 "B.CrtYd" user "Package Geometry/Place Bound Bottom")
		(35 "F.Fab" user "Ref Des/Assembly Top")
		(33 "B.Fab" user "Ref Des/Assembly Bottom")
	)
	(footprint ""
		(layer "F.Cu")
		(at 35.500056 -258.59994 180)
		(property "Reference" "GF6"
			(at 0 0 180)
			(layer "F.SilkS")
			(hide yes)
			(effects
				(font
					(size 1.27 1.27)
				)
			)
		)
		(property "Value" "GF-PCIE-36P-GP"
			(at -5.118354 -8.09879 180)
			(unlocked yes)
			(layer "F.Fab")
			(hide yes)
			(effects
				(font
					(size 1.016 1.016)
					(thickness 0.1524)
				)
			)
		)
		(property "Device Type" "GF-PCIE-36P"
			(at -5.118354 -9.62279 180)
			(unlocked yes)
			(layer "F.Fab")
			(hide yes)
			(effects
				(font
					(size 1.016 1.016)
					(thickness 0.1524)
				)
			)
		)
		(duplicate_pad_numbers_are_jumpers no)
		(fp_rect
			(start -13.8811 2.032)
			(end 9.8933 -6.223)
			(stroke
				(width 0)
				(type default)
			)
			(fill no)
			(layer "B.CrtYd")
		)
		(fp_rect
			(start -13.8811 2.032)
			(end 9.8933 -6.223)
			(stroke
				(width 0)
				(type default)
			)
			(fill no)
			(layer "F.CrtYd")
		)
		(fp_rect
			(start -13.8811 2.032)
			(end 9.8933 -6.223)
			(stroke
				(width 0)
				(type default)
			)
			(fill no)
			(layer "B.Fab")
		)
		(fp_rect
			(start -13.8811 2.032)
			(end 9.8933 -6.223)
			(stroke
				(width 0)
				(type default)
			)
			(fill no)
			(layer "F.Fab")
		)
		(fp_text user "02 Do not mirror"
			(at -10.94613 2.91084 180)
			(unlocked yes)
			(layer "F.Fab")
			(effects
				(font
					(size 1.016 1.016)
					(thickness 0.1524)
				)
				(justify left)
			)
		)
		(pad "A1" smd rect
			(at -11.49985 -2.0955 180)
			(size 0.7112 3.2004)
			(drill
				(offset 0 -0.4953)
			)
			(layers "F.Cu" "F.Mask" "F.Paste")
			(net "SAS_HDD_PRE0")
		)
		(pad "A2" smd rect
			(at -10.50036 -2.0955 180)
			(size 0.7112 4.191)
			(layers "F.Cu" "F.Mask" "F.Paste")
			(net "SAS_HDD_PRE1")
		)
		(pad "A3" smd rect
			(at -9.4996 -2.0955 180)
			(size 0.7112 4.191)
			(layers "F.Cu" "F.Mask" "F.Paste")
			(net "SAS_HDD_PRE2")
		)
		(pad "A4" smd rect
			(at -8.50011 -2.0955 180)
			(size 0.7112 4.191)
			(layers "F.Cu" "F.Mask" "F.Paste")
			(net "SAS_HDD_PRE3")
		)
		(pad "A5" smd rect
			(at -7.49935 -2.0955 180)
			(size 0.7112 4.191)
			(layers "F.Cu" "F.Mask" "F.Paste")
			(net "SAS_HDD_PRE4")
		)
		(pad "A6" smd rect
			(at -6.49986 -2.0955 180)
			(size 0.7112 4.191)
			(layers "F.Cu" "F.Mask" "F.Paste")
			(net "SAS_HDD_PRE5")
		)
		(pad "A7" smd rect
			(at -5.50037 -2.0955 180)
			(size 0.7112 4.191)
			(layers "F.Cu" "F.Mask" "F.Paste")
			(net "SAS_HDD_PRE6")
		)
		(pad "A8" smd rect
			(at -4.49961 -2.0955 180)
			(size 0.7112 4.191)
			(layers "F.Cu" "F.Mask" "F.Paste")
			(net "SAS_HDD_PRE7")
		)
		(pad "A9" smd rect
			(at -3.50012 -2.0955 180)
			(size 0.7112 4.191)
			(layers "F.Cu" "F.Mask" "F.Paste")
			(net "SAS_HDD_PRE8")
		)
		(pad "A10" smd rect
			(at -2.49936 -2.0955 180)
			(size 0.7112 4.191)
			(layers "F.Cu" "F.Mask" "F.Paste")
			(net "SAS_HDD_PRE9")
		)
		(pad "A11" smd rect
			(at -1.49987 -2.0955 180)
			(size 0.7112 4.191)
			(layers "F.Cu" "F.Mask" "F.Paste")
			(net "SAS_HDD_PRE10")
		)
		(pad "A12" smd rect
			(at 1.49987 -2.0955 180)
			(size 0.7112 4.191)
			(layers "F.Cu" "F.Mask" "F.Paste")
			(net "SAS_HDD_PRE11")
		)
		(pad "A13" smd rect
			(at 2.50063 -2.0955 180)
			(size 0.7112 4.191)
			(layers "F.Cu" "F.Mask" "F.Paste")
			(net "SAS_HDD_PRE12")
		)
		(pad "A14" smd rect
			(at 3.50012 -2.0955 180)
			(size 0.7112 4.191)
			(layers "F.Cu" "F.Mask" "F.Paste")
			(net "SAS_HDD_PRE13")
		)
		(pad "A15" smd rect
			(at 4.49961 -2.0955 180)
			(size 0.7112 4.191)
			(layers "F.Cu" "F.Mask" "F.Paste")
			(net "SAS_HDD_PRE14")
		)
		(pad "A16" smd rect
			(at 5.50037 -2.0955 180)
			(size 0.7112 4.191)
			(layers "F.Cu" "F.Mask" "F.Paste")
			(net "SELF_TRAY")
		)
		(pad "A17" smd rect
			(at 6.49986 -2.0955 180)
			(size 0.7112 4.191)
			(layers "F.Cu" "F.Mask" "F.Paste")
			(net "PEER_TRAY")
		)
		(pad "A18" smd rect
			(at 7.50062 -2.0955 180)
			(size 0.7112 4.191)
			(layers "F.Cu" "F.Mask" "F.Paste")
			(net "GND")
		)
		(pad "B1" smd rect
			(at -11.49985 -2.3495 180)
			(size 0.7112 4.191)
			(drill
				(offset 0 0.254)
			)
			(layers "F.Cu" "F.Mask" "F.Paste")
			(net "SAS_HDD_PWR0_PCIE")
		)
		(pad "B2" smd rect
			(at -10.50036 -2.3495 180)
			(size 0.7112 4.191)
			(drill
				(offset 0 0.254)
			)
			(layers "F.Cu" "F.Mask" "F.Paste")
			(net "SAS_HDD_PWR1_PCIE")
		)
		(pad "B3" smd rect
			(at -9.4996 -2.3495 180)
			(size 0.7112 4.191)
			(drill
				(offset 0 0.254)
			)
			(layers "F.Cu" "F.Mask" "F.Paste")
			(net "SAS_HDD_PWR2_PCIE")
		)
		(pad "B4" smd rect
			(at -8.50011 -2.3495 180)
			(size 0.7112 4.191)
			(drill
				(offset 0 0.254)
			)
			(layers "F.Cu" "F.Mask" "F.Paste")
			(net "SAS_HDD_PWR3_PCIE")
		)
		(pad "B5" smd rect
			(at -7.49935 -2.3495 180)
			(size 0.7112 4.191)
			(drill
				(offset 0 0.254)
			)
			(layers "F.Cu" "F.Mask" "F.Paste")
			(net "SAS_HDD_PWR4_PCIE")
		)
		(pad "B6" smd rect
			(at -6.49986 -2.3495 180)
			(size 0.7112 4.191)
			(drill
				(offset 0 0.254)
			)
			(layers "F.Cu" "F.Mask" "F.Paste")
			(net "SAS_HDD_PWR5_PCIE")
		)
		(pad "B7" smd rect
			(at -5.50037 -2.3495 180)
			(size 0.7112 4.191)
			(drill
				(offset 0 0.254)
			)
			(layers "F.Cu" "F.Mask" "F.Paste")
			(net "SAS_HDD_PWR6_PCIE")
		)
		(pad "B8" smd rect
			(at -4.49961 -2.3495 180)
			(size 0.7112 4.191)
			(drill
				(offset 0 0.254)
			)
			(layers "F.Cu" "F.Mask" "F.Paste")
			(net "SAS_HDD_PWR7_PCIE")
		)
		(pad "B9" smd rect
			(at -3.50012 -2.3495 180)
			(size 0.7112 4.191)
			(drill
				(offset 0 0.254)
			)
			(layers "F.Cu" "F.Mask" "F.Paste")
			(net "SAS_HDD_PWR8_PCIE")
		)
		(pad "B10" smd rect
			(at -2.49936 -2.3495 180)
			(size 0.7112 4.191)
			(drill
				(offset 0 0.254)
			)
			(layers "F.Cu" "F.Mask" "F.Paste")
			(net "SAS_HDD_PWR9_PCIE")
		)
		(pad "B11" smd rect
			(at -1.49987 -2.3495 180)
			(size 0.7112 4.191)
			(drill
				(offset 0 0.254)
			)
			(layers "F.Cu" "F.Mask" "F.Paste")
			(net "SAS_HDD_PWR10_PCIE")
		)
		(pad "B12" smd rect
			(at 1.49987 -2.3495 180)
			(size 0.7112 4.191)
			(drill
				(offset 0 0.254)
			)
			(layers "F.Cu" "F.Mask" "F.Paste")
			(net "SAS_HDD_PWR11_PCIE")
		)
		(pad "B13" smd rect
			(at 2.50063 -2.3495 180)
			(size 0.7112 4.191)
			(drill
				(offset 0 0.254)
			)
			(layers "F.Cu" "F.Mask" "F.Paste")
			(net "SAS_HDD_PWR12_PCIE")
		)
		(pad "B14" smd rect
			(at 3.50012 -2.3495 180)
			(size 0.7112 4.191)
			(drill
				(offset 0 0.254)
			)
			(layers "F.Cu" "F.Mask" "F.Paste")
			(net "SAS_HDD_PWR13_PCIE")
		)
		(pad "B15" smd rect
			(at 4.49961 -2.3495 180)
			(size 0.7112 4.191)
			(drill
				(offset 0 0.254)
			)
			(layers "F.Cu" "F.Mask" "F.Paste")
			(net "SAS_HDD_PWR14_PCIE")
		)
		(pad "B16" smd rect
			(at 5.50037 -2.3495 180)
			(size 0.7112 4.191)
			(drill
				(offset 0 0.254)
			)
			(layers "F.Cu" "F.Mask" "F.Paste")
			(net "SAS_HDD_PWR15_PCIE")
		)
		(pad "B17" smd rect
			(at 6.49986 -2.3495 180)
			(size 0.7112 3.2004)
			(drill
				(offset 0 -0.2413)
			)
			(layers "F.Cu" "F.Mask" "F.Paste")
			(net "PCIE_MATED#_A")
		)
		(pad "B18" smd rect
			(at 7.50062 -2.3495 180)
			(size 0.7112 4.191)
			(drill
				(offset 0 0.254)
			)
			(layers "F.Cu" "F.Mask" "F.Paste")
			(net "SAS_SEB_PEER_PRSNT")
		)
		(zone
			(layer "F.Cu")
			(hatch none 0.5)
			(connect_pads
				(clearance 0)
			)
			(min_thickness 0.25)
			(keepout
				(tracks allowed)
				(vias not_allowed)
				(pads allowed)
				(copperpour not_allowed)
				(footprints allowed)
			)
			(placement
				(enabled no)
				(sheetname "")
			)
			(fill
				(thermal_gap 0.5)
				(thermal_bridge_width 0.5)
				(island_removal_mode 0)
			)
			(polygon
				(pts
					(xy 48.370236 -259.61594) (xy 26.627836 -259.61594) (xy 26.627836 -253.39294) (xy 48.370236 -253.39294)
				)
			)
		)
		(zone
			(layer "F.Cu")
			(hatch none 0.5)
			(connect_pads
				(clearance 0)
			)
			(min_thickness 0.25)
			(keepout
				(tracks not_allowed)
				(vias allowed)
				(pads allowed)
				(copperpour not_allowed)
				(footprints allowed)
			)
			(placement
				(enabled no)
				(sheetname "")
			)
			(fill
				(thermal_gap 0.5)
				(thermal_bridge_width 0.5)
				(island_removal_mode 0)
			)
			(polygon
				(pts
					(xy 48.370236 -258.59994) (xy 48.370236 -259.61594) (xy 26.627836 -259.61594) (xy 26.627836 -258.59994)
				)
			)
		)
		(zone
			(layer "B.Cu")
			(hatch none 0.5)
			(connect_pads
				(clearance 0)
			)
			(min_thickness 0.25)
			(keepout
				(tracks not_allowed)
				(vias allowed)
				(pads allowed)
				(copperpour not_allowed)
				(footprints allowed)
			)
			(placement
				(enabled no)
				(sheetname "")
			)
			(fill
				(thermal_gap 0.5)
				(thermal_bridge_width 0.5)
				(island_removal_mode 0)
			)
			(polygon
				(pts
					(xy 48.370236 -259.61594) (xy 26.627836 -259.61594) (xy 26.627836 -258.59994) (xy 48.370236 -258.59994)
				)
			)
		)
		(zone
			(layer "B.Cu")
			(hatch none 0.5)
			(connect_pads
				(clearance 0)
			)
			(min_thickness 0.25)
			(keepout
				(tracks allowed)
				(vias not_allowed)
				(pads allowed)
				(copperpour not_allowed)
				(footprints allowed)
			)
			(placement
				(enabled no)
				(sheetname "")
			)
			(fill
				(thermal_gap 0.5)
				(thermal_bridge_width 0.5)
				(island_removal_mode 0)
			)
			(polygon
				(pts
					(xy 48.370236 -259.61594) (xy 26.627836 -259.61594) (xy 26.627836 -253.39294) (xy 48.370236 -253.39294)
				)
			)
		)
	)
	(footprint ""
		(layer "F.Cu")
		(at 305.299872 -193.747136)
		(property "Reference" "R163"
			(at 0 0 0)
			(layer "F.SilkS")
			(hide yes)
			(effects
				(font
					(size 1.27 1.27)
				)
			)
		)
		(property "Value" "4K7R2F-GP"
			(at 0.064008 -3.993896 0)
			(unlocked yes)
			(layer "F.Fab")
			(hide yes)
			(effects
				(font
					(size 1.016 1.016)
					(thickness 0.1524)
				)
			)
		)
		(property "Device Type" "R402H16"
			(at 0.064008 -5.517896 0)
			(unlocked yes)
			(layer "F.Fab")
			(hide yes)
			(effects
				(font
					(size 1.016 1.016)
					(thickness 0.1524)
				)
			)
		)
		(duplicate_pad_numbers_are_jumpers no)
		(fp_line
			(start -0.508 -0.9398)
			(end -0.508 0.9398)
			(stroke
				(width 0.1524)
				(type default)
			)
			(layer "F.SilkS")
		)
		(fp_line
			(start 0.508 -0.9398)
			(end -0.508 -0.9398)
			(stroke
				(width 0.1524)
				(type default)
			)
			(layer "F.SilkS")
		)
		(fp_rect
			(start -0.508 0.9398)
			(end 0.508 -0.9398)
			(stroke
				(width 0)
				(type default)
			)
			(fill no)
			(layer "F.CrtYd")
		)
		(fp_rect
			(start -0.508 0.9398)
			(end 0.508 -0.9398)
			(stroke
				(width 0)
				(type default)
			)
			(fill no)
			(layer "F.Fab")
		)
		(pad "1" smd custom
			(at 0 -0.4445)
			(size 0.1397 0.1397)
			(layers "F.Cu" "F.Mask" "F.Paste")
			(net "LED_DR_A0")
			(options
				(clearance outline)
				(anchor circle)
			)
			(primitives
				(gr_poly
					(pts
						(arc
							(start -0.1778 -0.2794)
							(mid -0.249642 -0.249642)
							(end -0.2794 -0.1778)
						)
						(arc
							(start -0.2794 0.1778)
							(mid -0.249642 0.249642)
							(end -0.1778 0.2794)
						)
						(arc
							(start 0.1778 0.2794)
							(mid 0.249642 0.249642)
							(end 0.2794 0.1778)
						)
						(arc
							(start 0.2794 -0.1778)
							(mid 0.249642 -0.249642)
							(end 0.1778 -0.2794)
						)
					)
					(width 0)
					(fill yes)
				)
			)
		)
		(pad "2" smd custom
			(at 0 0.4445)
			(size 0.1397 0.1397)
			(layers "F.Cu" "F.Mask" "F.Paste")
			(net "GND")
			(options
				(clearance outline)
				(anchor circle)
			)
			(primitives
				(gr_poly
					(pts
						(arc
							(start -0.1778 -0.2794)
							(mid -0.249642 -0.249642)
							(end -0.2794 -0.1778)
						)
						(arc
							(start -0.2794 0.1778)
							(mid -0.249642 0.249642)
							(end -0.1778 0.2794)
						)
						(arc
							(start 0.1778 0.2794)
							(mid 0.249642 0.249642)
							(end 0.2794 0.1778)
						)
						(arc
							(start 0.2794 -0.1778)
							(mid 0.249642 -0.249642)
							(end 0.1778 -0.2794)
						)
					)
					(width 0)
					(fill yes)
				)
			)
		)
	)
	(footprint ""
		(layer "F.Cu")
		(at 325.374 -179.705)
		(property "Reference" "R5769"
			(at 0 0 0)
			(layer "F.SilkS")
			(hide yes)
			(effects
				(font
					(size 1.27 1.27)
				)
			)
		)
		(property "Value" "1KR2F-3-GP"
			(at 0.064008 -3.993896 0)
			(unlocked yes)
			(layer "F.Fab")
			(hide yes)
			(effects
				(font
					(size 1.016 1.016)
					(thickness 0.1524)
				)
			)
		)
		(property "Device Type" "R402H16"
			(at 0.064008 -5.517896 0)
			(unlocked yes)
			(layer "F.Fab")
			(hide yes)
			(effects
				(font
					(size 1.016 1.016)
					(thickness 0.1524)
				)
			)
		)
		(duplicate_pad_numbers_are_jumpers no)
		(fp_line
			(start -0.508 -0.9398)
			(end -0.508 0.9398)
			(stroke
				(width 0.1524)
				(type default)
			)
			(layer "F.SilkS")
		)
		(fp_line
			(start 0.508 -0.9398)
			(end -0.508 -0.9398)
			(stroke
				(width 0.1524)
				(type default)
			)
			(layer "F.SilkS")
		)
		(fp_rect
			(start -0.508 0.9398)
			(end 0.508 -0.9398)
			(stroke
				(width 0)
				(type default)
			)
			(fill no)
			(layer "F.CrtYd")
		)
		(fp_rect
			(start -0.508 0.9398)
			(end 0.508 -0.9398)
			(stroke
				(width 0)
				(type default)
			)
			(fill no)
			(layer "F.Fab")
		)
		(pad "1" smd custom
			(at 0 -0.4445)
			(size 0.1397 0.1397)
			(layers "F.Cu" "F.Mask" "F.Paste")
			(net "P1V5_C")
			(options
				(clearance outline)
				(anchor circle)
			)
			(primitives
				(gr_poly
					(pts
						(arc
							(start -0.1778 -0.2794)
							(mid -0.249642 -0.249642)
							(end -0.2794 -0.1778)
						)
						(arc
							(start -0.2794 0.1778)
							(mid -0.249642 0.249642)
							(end -0.1778 0.2794)
						)
						(arc
							(start 0.1778 0.2794)
							(mid 0.249642 0.249642)
							(end 0.2794 0.1778)
						)
						(arc
							(start 0.2794 -0.1778)
							(mid 0.249642 -0.249642)
							(end 0.1778 -0.2794)
						)
					)
					(width 0)
					(fill yes)
				)
			)
		)
		(pad "2" smd custom
			(at 0 0.4445)
			(size 0.1397 0.1397)
			(layers "F.Cu" "F.Mask" "F.Paste")
			(net "ADC_P1V5_C")
			(options
				(clearance outline)
				(anchor circle)
			)
			(primitives
				(gr_poly
					(pts
						(arc
							(start -0.1778 -0.2794)
							(mid -0.249642 -0.249642)
							(end -0.2794 -0.1778)
						)
						(arc
							(start -0.2794 0.1778)
							(mid -0.249642 0.249642)
							(end -0.1778 0.2794)
						)
						(arc
							(start 0.1778 0.2794)
							(mid 0.249642 0.249642)
							(end 0.2794 0.1778)
						)
						(arc
							(start 0.2794 -0.1778)
							(mid 0.249642 -0.249642)
							(end 0.1778 -0.2794)
						)
					)
					(width 0)
					(fill yes)
				)
			)
		)
	)
	(footprint ""
		(layer "F.Cu")
		(at 317.881 -51.181 90)
		(property "Reference" "C282"
			(at 0 0 90)
			(layer "F.SilkS")
			(hide yes)
			(effects
				(font
					(size 1.27 1.27)
				)
			)
		)
		(property "Value" "SCD1U25V2KX-2-GP"
			(at 1.1811 -2.7051 90)
			(unlocked yes)
			(layer "F.Fab")
			(hide yes)
			(effects
				(font
					(size 1.016 1.016)
					(thickness 0.1524)
				)
			)
		)
		(property "Device Type" "C402H22"
			(at 1.1811 -4.2291 90)
			(unlocked yes)
			(layer "F.Fab")
			(hide yes)
			(effects
				(font
					(size 1.016 1.016)
					(thickness 0.1524)
				)
			)
		)
		(duplicate_pad_numbers_are_jumpers no)
		(fp_rect
			(start -0.4318 0.9525)
			(end 0.4318 -0.9525)
			(stroke
				(width 0)
				(type default)
			)
			(fill no)
			(layer "F.CrtYd")
		)
		(fp_rect
			(start -0.4318 0.9525)
			(end 0.4318 -0.9525)
			(stroke
				(width 0)
				(type default)
			)
			(fill no)
			(layer "F.Fab")
		)
		(pad "1" smd custom
			(at 0 -0.4445 90)
			(size 0.1524 0.1524)
			(layers "F.Cu" "F.Mask" "F.Paste")
			(net "P5V_STBY")
			(options
				(clearance outline)
				(anchor circle)
			)
			(primitives
				(gr_poly
					(pts
						(arc
							(start 0.3048 -0.2032)
							(mid 0.275042 -0.275042)
							(end 0.2032 -0.3048)
						)
						(arc
							(start -0.2032 -0.3048)
							(mid -0.275042 -0.275042)
							(end -0.3048 -0.2032)
						)
						(arc
							(start -0.3048 0.2032)
							(mid -0.275042 0.275042)
							(end -0.2032 0.3048)
						)
						(arc
							(start 0.2032 0.3048)
							(mid 0.275042 0.275042)
							(end 0.3048 0.2032)
						)
					)
					(width 0)
					(fill yes)
				)
			)
		)
		(pad "2" smd custom
			(at 0 0.4445 90)
			(size 0.1524 0.1524)
			(layers "F.Cu" "F.Mask" "F.Paste")
			(net "GND")
			(options
				(clearance outline)
				(anchor circle)
			)
			(primitives
				(gr_poly
					(pts
						(arc
							(start 0.3048 -0.2032)
							(mid 0.275042 -0.275042)
							(end 0.2032 -0.3048)
						)
						(arc
							(start -0.2032 -0.3048)
							(mid -0.275042 -0.275042)
							(end -0.3048 -0.2032)
						)
						(arc
							(start -0.3048 0.2032)
							(mid -0.275042 0.275042)
							(end -0.2032 0.3048)
						)
						(arc
							(start 0.2032 0.3048)
							(mid 0.275042 0.275042)
							(end 0.3048 0.2032)
						)
					)
					(width 0)
					(fill yes)
				)
			)
		)
	)
)
